(kicad_pcb
	(version 20260206)
	(generator "pcbnew")
	(generator_version "10.0")
	(general
		(thickness 1.6)
		(legacy_teardrops no)
	)
	(paper "A4")
	(title_block
		(title "04192023_DAF0TMB3IC0_F0TG_MB_C_brd_V02_OCP.brd")
		(comment 1 "Grand Teton / footprints 3187-3192 of 8354")
	)
	(layers
		(0 "F.Cu" signal "TOP")
		(4 "In1.Cu" signal "GND")
		(6 "In2.Cu" signal "IN1")
		(8 "In3.Cu" signal "GND1")
		(10 "In4.Cu" signal "IN2")
		(12 "In5.Cu" signal "GND2")
		(14 "In6.Cu" signal "IN3")
		(16 "In7.Cu" signal "GND3")
		(18 "In8.Cu" signal "VCC")
		(20 "In9.Cu" signal "VCC1")
		(22 "In10.Cu" signal "GND4")
		(24 "In11.Cu" signal "IN4")
		(26 "In12.Cu" signal "GND5")
		(28 "In13.Cu" signal "IN5")
		(30 "In14.Cu" signal "GND6")
		(32 "In15.Cu" signal "IN6")
		(34 "In16.Cu" signal "GND7")
		(2 "B.Cu" signal "BOTTOM")
		(9 "F.Adhes" user "F.Adhesive")
		(11 "B.Adhes" user "B.Adhesive")
		(13 "F.Paste" user "Package Geometry/Pastemask Top")
		(15 "B.Paste" user "Package Geometry/Pastemask Bottom")
		(5 "F.SilkS" user "Ref Des/Silkscreen Top")
		(7 "B.SilkS" user "Ref Des/Silkscreen Bottom")
		(1 "F.Mask" user "Board Geometry/Soldermask Top")
		(3 "B.Mask" user "Board Geometry/Soldermask Bottom")
		(17 "Dwgs.User" user "User.Drawings")
		(19 "Cmts.User" user "User.Comments")
		(21 "Eco1.User" user "User.Eco1")
		(23 "Eco2.User" user "User.Eco2")
		(25 "Edge.Cuts" user "Board Geometry/Outline")
		(27 "Margin" user)
		(31 "F.CrtYd" user "Package Geometry/Place Bound Top")
		(29 "B.CrtYd" user "Package Geometry/Place Bound Bottom")
		(35 "F.Fab" user "Ref Des/Assembly Top")
		(33 "B.Fab" user "Ref Des/Assembly Bottom")
	)
	(footprint ""
		(layer "F.Cu")
		(at 171.196 -106.136948 180)
		(property "Reference" "R164"
			(at 0 0 180)
			(layer "F.SilkS")
			(hide yes)
			(effects
				(font
					(size 1.27 1.27)
				)
			)
		)
		(property "Value" ""
			(at 0 0 180)
			(layer "F.Fab")
			(effects
				(font
					(size 1.27 1.27)
				)
			)
		)
		(duplicate_pad_numbers_are_jumpers no)
		(fp_line
			(start 0.7874 0.4064)
			(end -0.7874 0.4064)
			(stroke
				(width 0.1524)
				(type default)
			)
			(layer "F.SilkS")
		)
		(fp_line
			(start 0.7874 -0.4064)
			(end 0.7874 0.4064)
			(stroke
				(width 0.1524)
				(type default)
			)
			(layer "F.SilkS")
		)
		(fp_line
			(start -0.7874 0.4064)
			(end -0.7874 -0.4064)
			(stroke
				(width 0.1524)
				(type default)
			)
			(layer "F.SilkS")
		)
		(fp_line
			(start -0.7874 -0.4064)
			(end 0.7874 -0.4064)
			(stroke
				(width 0.1524)
				(type default)
			)
			(layer "F.SilkS")
		)
		(fp_line
			(start 0.67945 0.3048)
			(end 0.120396 0.3048)
			(stroke
				(width 0.1)
				(type default)
			)
			(layer "F.Fab")
		)
		(fp_line
			(start 0.67945 -0.3048)
			(end 0.67945 0.3048)
			(stroke
				(width 0.1)
				(type default)
			)
			(layer "F.Fab")
		)
		(fp_line
			(start 0.12065 -0.2794)
			(end 0.12065 -0.3048)
			(stroke
				(width 0.1)
				(type default)
			)
			(layer "F.Fab")
		)
		(fp_line
			(start 0.12065 -0.3048)
			(end 0.67945 -0.3048)
			(stroke
				(width 0.1)
				(type default)
			)
			(layer "F.Fab")
		)
		(fp_line
			(start 0.120396 0.3048)
			(end 0.120396 0.2794)
			(stroke
				(width 0.1)
				(type default)
			)
			(layer "F.Fab")
		)
		(fp_line
			(start 0.120396 0.2794)
			(end -0.12065 0.2794)
			(stroke
				(width 0.1)
				(type default)
			)
			(layer "F.Fab")
		)
		(fp_line
			(start -0.12065 0.3048)
			(end -0.67945 0.3048)
			(stroke
				(width 0.1)
				(type default)
			)
			(layer "F.Fab")
		)
		(fp_line
			(start -0.12065 0.2794)
			(end -0.12065 0.3048)
			(stroke
				(width 0.1)
				(type default)
			)
			(layer "F.Fab")
		)
		(fp_line
			(start -0.12065 -0.2794)
			(end 0.12065 -0.2794)
			(stroke
				(width 0.1)
				(type default)
			)
			(layer "F.Fab")
		)
		(fp_line
			(start -0.12065 -0.305054)
			(end -0.12065 -0.2794)
			(stroke
				(width 0.1)
				(type default)
			)
			(layer "F.Fab")
		)
		(fp_line
			(start -0.67945 0.3048)
			(end -0.67945 -0.305054)
			(stroke
				(width 0.1)
				(type default)
			)
			(layer "F.Fab")
		)
		(fp_line
			(start -0.67945 -0.305054)
			(end -0.12065 -0.305054)
			(stroke
				(width 0.1)
				(type default)
			)
			(layer "F.Fab")
		)
		(pad "1" smd circle
			(at -0.40005 0 180)
			(size 0 0)
			(layers "F.Cu" "F.Mask" "F.Paste")
			(net "FM_I3C_CPU0_MUX0_R_SEL")
		)
		(pad "2" smd circle
			(at 0.40005 0 180)
			(size 0 0)
			(layers "F.Cu" "F.Mask" "F.Paste")
			(net "FM_I3C_CPU0_MUX0_SEL")
		)
	)
	(footprint ""
		(layer "F.Cu")
		(at 444.36792 -437.428132 90)
		(property "Reference" "R4165"
			(at 0 0 90)
			(layer "F.SilkS")
			(hide yes)
			(effects
				(font
					(size 1.27 1.27)
				)
			)
		)
		(property "Value" ""
			(at 0 0 90)
			(layer "F.Fab")
			(effects
				(font
					(size 1.27 1.27)
				)
			)
		)
		(duplicate_pad_numbers_are_jumpers no)
		(fp_line
			(start 0.7874 -0.4064)
			(end 0.7874 0.4064)
			(stroke
				(width 0.1524)
				(type default)
			)
			(layer "F.SilkS")
		)
		(fp_line
			(start -0.7874 -0.4064)
			(end 0.7874 -0.4064)
			(stroke
				(width 0.1524)
				(type default)
			)
			(layer "F.SilkS")
		)
		(fp_line
			(start 0.7874 0.4064)
			(end -0.7874 0.4064)
			(stroke
				(width 0.1524)
				(type default)
			)
			(layer "F.SilkS")
		)
		(fp_line
			(start -0.7874 0.4064)
			(end -0.7874 -0.4064)
			(stroke
				(width 0.1524)
				(type default)
			)
			(layer "F.SilkS")
		)
		(fp_line
			(start -0.12065 -0.305054)
			(end -0.12065 -0.2794)
			(stroke
				(width 0.1)
				(type default)
			)
			(layer "F.Fab")
		)
		(fp_line
			(start -0.67945 -0.305054)
			(end -0.12065 -0.305054)
			(stroke
				(width 0.1)
				(type default)
			)
			(layer "F.Fab")
		)
		(fp_line
			(start 0.67945 -0.3048)
			(end 0.67945 0.3048)
			(stroke
				(width 0.1)
				(type default)
			)
			(layer "F.Fab")
		)
		(fp_line
			(start 0.12065 -0.3048)
			(end 0.67945 -0.3048)
			(stroke
				(width 0.1)
				(type default)
			)
			(layer "F.Fab")
		)
		(fp_line
			(start 0.12065 -0.2794)
			(end 0.12065 -0.3048)
			(stroke
				(width 0.1)
				(type default)
			)
			(layer "F.Fab")
		)
		(fp_line
			(start -0.12065 -0.2794)
			(end 0.12065 -0.2794)
			(stroke
				(width 0.1)
				(type default)
			)
			(layer "F.Fab")
		)
		(fp_line
			(start 0.120396 0.2794)
			(end -0.12065 0.2794)
			(stroke
				(width 0.1)
				(type default)
			)
			(layer "F.Fab")
		)
		(fp_line
			(start -0.12065 0.2794)
			(end -0.12065 0.3048)
			(stroke
				(width 0.1)
				(type default)
			)
			(layer "F.Fab")
		)
		(fp_line
			(start 0.67945 0.3048)
			(end 0.120396 0.3048)
			(stroke
				(width 0.1)
				(type default)
			)
			(layer "F.Fab")
		)
		(fp_line
			(start 0.120396 0.3048)
			(end 0.120396 0.2794)
			(stroke
				(width 0.1)
				(type default)
			)
			(layer "F.Fab")
		)
		(fp_line
			(start -0.12065 0.3048)
			(end -0.67945 0.3048)
			(stroke
				(width 0.1)
				(type default)
			)
			(layer "F.Fab")
		)
		(fp_line
			(start -0.67945 0.3048)
			(end -0.67945 -0.305054)
			(stroke
				(width 0.1)
				(type default)
			)
			(layer "F.Fab")
		)
		(pad "1" smd circle
			(at -0.40005 0 90)
			(size 0 0)
			(layers "F.Cu" "F.Mask" "F.Paste")
			(net "P3V3_AUX")
		)
		(pad "2" smd circle
			(at 0.40005 0 90)
			(size 0 0)
			(layers "F.Cu" "F.Mask" "F.Paste")
			(net "GPU_3V3IO_RSVD4_N")
		)
	)
	(footprint ""
		(layer "F.Cu")
		(at 148.494242 -110.731046)
		(property "Reference" "R996"
			(at 0 0 0)
			(layer "F.SilkS")
			(hide yes)
			(effects
				(font
					(size 1.27 1.27)
				)
			)
		)
		(property "Value" ""
			(at 0 0 0)
			(layer "F.Fab")
			(effects
				(font
					(size 1.27 1.27)
				)
			)
		)
		(duplicate_pad_numbers_are_jumpers no)
		(fp_line
			(start -0.7874 -0.4064)
			(end 0.7874 -0.4064)
			(stroke
				(width 0.1524)
				(type default)
			)
			(layer "F.SilkS")
		)
		(fp_line
			(start -0.7874 0.4064)
			(end -0.7874 -0.4064)
			(stroke
				(width 0.1524)
				(type default)
			)
			(layer "F.SilkS")
		)
		(fp_line
			(start 0.7874 -0.4064)
			(end 0.7874 0.4064)
			(stroke
				(width 0.1524)
				(type default)
			)
			(layer "F.SilkS")
		)
		(fp_line
			(start 0.7874 0.4064)
			(end -0.7874 0.4064)
			(stroke
				(width 0.1524)
				(type default)
			)
			(layer "F.SilkS")
		)
		(fp_line
			(start -0.67945 -0.305054)
			(end -0.12065 -0.305054)
			(stroke
				(width 0.1)
				(type default)
			)
			(layer "F.Fab")
		)
		(fp_line
			(start -0.67945 0.3048)
			(end -0.67945 -0.305054)
			(stroke
				(width 0.1)
				(type default)
			)
			(layer "F.Fab")
		)
		(fp_line
			(start -0.12065 -0.305054)
			(end -0.12065 -0.2794)
			(stroke
				(width 0.1)
				(type default)
			)
			(layer "F.Fab")
		)
		(fp_line
			(start -0.12065 -0.2794)
			(end 0.12065 -0.2794)
			(stroke
				(width 0.1)
				(type default)
			)
			(layer "F.Fab")
		)
		(fp_line
			(start -0.12065 0.2794)
			(end -0.12065 0.3048)
			(stroke
				(width 0.1)
				(type default)
			)
			(layer "F.Fab")
		)
		(fp_line
			(start -0.12065 0.3048)
			(end -0.67945 0.3048)
			(stroke
				(width 0.1)
				(type default)
			)
			(layer "F.Fab")
		)
		(fp_line
			(start 0.120396 0.2794)
			(end -0.12065 0.2794)
			(stroke
				(width 0.1)
				(type default)
			)
			(layer "F.Fab")
		)
		(fp_line
			(start 0.120396 0.3048)
			(end 0.120396 0.2794)
			(stroke
				(width 0.1)
				(type default)
			)
			(layer "F.Fab")
		)
		(fp_line
			(start 0.12065 -0.3048)
			(end 0.67945 -0.3048)
			(stroke
				(width 0.1)
				(type default)
			)
			(layer "F.Fab")
		)
		(fp_line
			(start 0.12065 -0.2794)
			(end 0.12065 -0.3048)
			(stroke
				(width 0.1)
				(type default)
			)
			(layer "F.Fab")
		)
		(fp_line
			(start 0.67945 -0.3048)
			(end 0.67945 0.3048)
			(stroke
				(width 0.1)
				(type default)
			)
			(layer "F.Fab")
		)
		(fp_line
			(start 0.67945 0.3048)
			(end 0.120396 0.3048)
			(stroke
				(width 0.1)
				(type default)
			)
			(layer "F.Fab")
		)
		(pad "1" smd circle
			(at -0.40005 0)
			(size 0 0)
			(layers "F.Cu" "F.Mask" "F.Paste")
			(net "P1V8_AUX")
		)
		(pad "2" smd circle
			(at 0.40005 0)
			(size 0 0)
			(layers "F.Cu" "F.Mask" "F.Paste")
			(net "SCM_IRQ_1V8_N")
		)
	)
	(footprint ""
		(layer "F.Cu")
		(at 266.862306 -333.031846)
		(property "Reference" "TP2"
			(at -5.423916 0.05207 0)
			(unlocked yes)
			(layer "F.SilkS")
			(effects
				(font
					(size 0.7874 0.5842)
					(thickness 0.1524)
				)
				(justify left)
			)
		)
		(property "Value" ""
			(at 0 0 0)
			(layer "F.Fab")
			(effects
				(font
					(size 1.27 1.27)
				)
			)
		)
		(duplicate_pad_numbers_are_jumpers no)
		(pad "1" smd circle
			(at 0 0)
			(size 0.762 0.762)
			(layers "F.Cu" "F.Mask" "F.Paste")
			(net "VSENSE_VSS_SENSE_B_P0")
		)
	)
	(footprint ""
		(layer "F.Cu")
		(at 62.47257 -37.307266 180)
		(property "Reference" "Q118"
			(at 1.09982 -1.964944 0)
			(unlocked yes)
			(layer "F.SilkS")
			(effects
				(font
					(size 0.7874 0.5842)
					(thickness 0.1524)
				)
				(justify left)
			)
		)
		(property "Value" ""
			(at 0 0 180)
			(layer "F.Fab")
			(effects
				(font
					(size 1.27 1.27)
				)
			)
		)
		(duplicate_pad_numbers_are_jumpers no)
		(fp_line
			(start 1.332738 1.100074)
			(end -1.332738 1.100074)
			(stroke
				(width 0.1524)
				(type default)
			)
			(layer "F.SilkS")
		)
		(fp_line
			(start 1.332738 -1.100074)
			(end 1.332738 1.100074)
			(stroke
				(width 0.1524)
				(type default)
			)
			(layer "F.SilkS")
		)
		(fp_line
			(start 0.4826 -1.100074)
			(end 1.332738 -1.100074)
			(stroke
				(width 0.1524)
				(type default)
			)
			(layer "F.SilkS")
		)
		(fp_line
			(start 0 -0.541274)
			(end 0.4826 -1.100074)
			(stroke
				(width 0.1524)
				(type default)
			)
			(layer "F.SilkS")
		)
		(fp_line
			(start -0.4826 -1.100074)
			(end 0 -0.541274)
			(stroke
				(width 0.1524)
				(type default)
			)
			(layer "F.SilkS")
		)
		(fp_line
			(start -1.332738 1.100074)
			(end -1.332738 -1.100074)
			(stroke
				(width 0.1524)
				(type default)
			)
			(layer "F.SilkS")
		)
		(fp_line
			(start -1.332738 -1.100074)
			(end -0.4826 -1.100074)
			(stroke
				(width 0.1524)
				(type default)
			)
			(layer "F.SilkS")
		)
		(fp_poly
			(pts
				(xy -1.945132 -0.676402) (xy -2.647188 -0.325374) (xy -2.647188 -1.02743)
			)
			(stroke
				(width 0)
				(type default)
			)
			(fill yes)
			(layer "F.SilkS")
		)
		(fp_line
			(start 0.674878 1.100074)
			(end -0.674878 1.100074)
			(stroke
				(width 0.1)
				(type default)
			)
			(layer "F.Fab")
		)
		(fp_line
			(start 0.674878 -1.100074)
			(end 0.674878 1.100074)
			(stroke
				(width 0.1)
				(type default)
			)
			(layer "F.Fab")
		)
		(fp_line
			(start -0.674878 1.100074)
			(end -0.674878 -1.100074)
			(stroke
				(width 0.1)
				(type default)
			)
			(layer "F.Fab")
		)
		(fp_line
			(start -0.674878 -1.100074)
			(end 0.674878 -1.100074)
			(stroke
				(width 0.1)
				(type default)
			)
			(layer "F.Fab")
		)
		(fp_poly
			(pts
				(xy -2.2352 -0.298958) (xy -2.2352 -1.001014) (xy -1.533144 -0.649986)
			)
			(stroke
				(width 0)
				(type default)
			)
			(fill yes)
			(layer "F.Fab")
		)
		(pad "1" smd rect
			(at -0.94996 -0.649986 270)
			(size 0.4318 0.508)
			(layers "F.Cu" "F.Mask" "F.Paste")
			(net "GND")
		)
		(pad "2" smd rect
			(at -0.94996 0 270)
			(size 0.4318 0.508)
			(layers "F.Cu" "F.Mask" "F.Paste")
			(net "P12V_OCP_EN_2_R")
		)
		(pad "3" smd rect
			(at -0.94996 0.649986 270)
			(size 0.4318 0.508)
			(layers "F.Cu" "F.Mask" "F.Paste")
			(net "P12V_OCP_UV_2_R")
		)
		(pad "4" smd rect
			(at 0.94996 0.649986 270)
			(size 0.4318 0.508)
			(layers "F.Cu" "F.Mask" "F.Paste")
			(net "GND")
		)
		(pad "5" smd rect
			(at 0.94996 0 270)
			(size 0.4318 0.508)
			(layers "F.Cu" "F.Mask" "F.Paste")
			(net "P12V_OCP_2_EN_G")
		)
		(pad "6" smd rect
			(at 0.94996 -0.649986 270)
			(size 0.4318 0.508)
			(layers "F.Cu" "F.Mask" "F.Paste")
			(net "P12V_OCP_2_EN_G")
		)
	)
	(footprint ""
		(layer "F.Cu")
		(at 488.03433 -142.808198 90)
		(property "Reference" "X8010"
			(at -1.947672 1.593342 0)
			(unlocked yes)
			(layer "F.SilkS")
			(effects
				(font
					(size 0.7874 0.5842)
					(thickness 0.1524)
				)
				(justify left)
			)
		)
		(property "Value" ""
			(at 0 0 90)
			(layer "F.Fab")
			(effects
				(font
					(size 1.27 1.27)
				)
			)
		)
		(property "Device Type" "TP_TDR_4P_FTS_TH-TP_TDR_4P_DIP,EMPTY,TP15"
			(at 1.30175 1.27 180)
			(unlocked yes)
			(layer "F.Fab")
			(hide yes)
			(effects
				(font
					(size 0.635 0.4064)
					(thickness 0.1524)
				)
			)
		)
		(property "User Part Number" "N_A"
			(at 1.30175 1.27 180)
			(unlocked yes)
			(layer "Cmts.User")
			(hide yes)
			(effects
				(font
					(size 0.635 0.4064)
					(thickness 0.1524)
				)
			)
		)
		(duplicate_pad_numbers_are_jumpers no)
		(fp_line
			(start 2.54 -1.27)
			(end 0 -1.27)
			(stroke
				(width 0.1524)
				(type default)
			)
			(layer "F.SilkS")
		)
		(fp_line
			(start 0 -1.27)
			(end 0 -0.635)
			(stroke
				(width 0.1524)
				(type default)
			)
			(layer "F.SilkS")
		)
		(fp_line
			(start 2.54 -1.1303)
			(end 2.54 -1.27)
			(stroke
				(width 0.1524)
				(type default)
			)
			(layer "F.SilkS")
		)
		(fp_line
			(start 0 0.635)
			(end 0 1.905)
			(stroke
				(width 0.1524)
				(type default)
			)
			(layer "F.SilkS")
		)
		(fp_line
			(start 2.54 1.4097)
			(end 2.54 1.1303)
			(stroke
				(width 0.1524)
				(type default)
			)
			(layer "F.SilkS")
		)
		(fp_line
			(start 0 3.175)
			(end 0 3.81)
			(stroke
				(width 0.1524)
				(type default)
			)
			(layer "F.SilkS")
		)
		(fp_line
			(start 2.54 3.81)
			(end 2.54 3.6703)
			(stroke
				(width 0.1524)
				(type default)
			)
			(layer "F.SilkS")
		)
		(fp_line
			(start 0 3.81)
			(end 2.54 3.81)
			(stroke
				(width 0.1524)
				(type default)
			)
			(layer "F.SilkS")
		)
		(fp_poly
			(pts
				(xy -2.285746 -0.762) (xy -0.761746 0) (xy -2.285746 0.762)
			)
			(stroke
				(width 0)
				(type default)
			)
			(fill yes)
			(layer "F.SilkS")
		)
		(fp_line
			(start 2.54 -1.27)
			(end 0 -1.27)
			(stroke
				(width 0.1)
				(type default)
			)
			(layer "F.Fab")
		)
		(fp_line
			(start 0 -1.27)
			(end 0 3.81)
			(stroke
				(width 0.1)
				(type default)
			)
			(layer "F.Fab")
		)
		(fp_line
			(start 2.54 3.81)
			(end 2.54 -1.27)
			(stroke
				(width 0.1)
				(type default)
			)
			(layer "F.Fab")
		)
		(fp_line
			(start 0 3.81)
			(end 2.54 3.81)
			(stroke
				(width 0.1)
				(type default)
			)
			(layer "F.Fab")
		)
		(fp_poly
			(pts
				(xy -0.761746 0) (xy -2.285746 -0.762) (xy -2.285746 0.762)
			)
			(stroke
				(width 0)
				(type default)
			)
			(fill yes)
			(layer "F.Fab")
		)
		(pad "1" thru_hole circle
			(at 0 0 90)
			(size 1.0033 1.0033)
			(drill 0.249936)
			(layers "*.Cu" "*.Mask")
			(remove_unused_layers no)
			(net "TDR_DIFF_85_IN3_DN")
			(clearance 0.10795)
			(thermal_gap 0.10795)
			(padstack
				(mode front_inner_back)
				(layer "Inner"
					(shape circle)
					(size 0.8001 0.8001)
					(clearance 0.1524)
				)
				(layer "B.Cu"
					(shape circle)
					(size 1.0033 1.0033)
					(clearance 0.10795)
				)
			)
		)
		(pad "2" thru_hole circle
			(at 2.54 0 90)
			(size 1.9939 1.9939)
			(drill 0.249936)
			(layers "*.Cu" "*.Mask")
			(remove_unused_layers no)
			(net "T1_GND")
			(clearance 0.10795)
			(thermal_gap 0.10795)
			(padstack
				(mode front_inner_back)
				(layer "Inner"
					(shape circle)
					(size 0.8001 0.8001)
					(clearance 0.1524)
				)
				(layer "B.Cu"
					(shape circle)
					(size 1.9939 1.9939)
					(clearance 0.10795)
				)
			)
		)
		(pad "3" thru_hole circle
			(at 2.54 2.54 90)
			(size 1.9939 1.9939)
			(drill 0.249936)
			(layers "*.Cu" "*.Mask")
			(remove_unused_layers no)
			(net "T1_GND")
			(clearance 0.10795)
			(thermal_gap 0.10795)
			(padstack
				(mode front_inner_back)
				(layer "Inner"
					(shape circle)
					(size 0.8001 0.8001)
					(clearance 0.1524)
				)
				(layer "B.Cu"
					(shape circle)
					(size 1.9939 1.9939)
					(clearance 0.10795)
				)
			)
		)
		(pad "4" thru_hole circle
			(at 0 2.54 90)
			(size 1.0033 1.0033)
			(drill 0.249936)
			(layers "*.Cu" "*.Mask")
			(remove_unused_layers no)
			(net "TDR_DIFF_85_IN3_DP")
			(clearance 0.10795)
			(thermal_gap 0.10795)
			(padstack
				(mode front_inner_back)
				(layer "Inner"
					(shape circle)
					(size 0.8001 0.8001)
					(clearance 0.1524)
				)
				(layer "B.Cu"
					(shape circle)
					(size 1.0033 1.0033)
					(clearance 0.10795)
				)
			)
		)
	)
)
